# BASEBOARD_FAB2 (Tioga Pass) — schematic netlist excerpt (pin names and nets, part order shuffled) for the footprints in the layout excerpt that follows; sources: Cadence DE-HDL packaged netlist, KiCad conversion of Wiwynn_Tioga_Pass_MB.brd

C5M2  CAP_A  47UF 4V 20% X5R  pkg 0603V  page 220 : A = PVDDQ_DEF ; B = GND
C3R1  CAP_A  0.1UF 16V 10% X7R  pkg 0402V  page 192 : A = P3V3_STBY ; B = GND
C8T7  CAP_A  47UF 4V 20% X5R  pkg 0603V  page 225 : A = PVDDQ_GHJ ; B = GND

(kicad_pcb
	(version 20260206)
	(generator "pcbnew")
	(generator_version "10.0")
	(general
		(thickness 1.6)
		(legacy_teardrops no)
	)
	(paper "A4")
	(title_block
		(title "Wiwynn_Tioga_Pass_MB.brd")
		(comment 1 "Tioga Pass / footprints 3893-3895 of 4770")
	)
	(layers
		(0 "F.Cu" signal "TOP")
		(4 "In1.Cu" signal "L2GND")
		(6 "In2.Cu" signal "L3")
		(8 "In3.Cu" signal "L4GND")
		(10 "In4.Cu" signal "L5")
		(12 "In5.Cu" signal "L6GND")
		(14 "In6.Cu" signal "L7VCC")
		(16 "In7.Cu" signal "L8VCC")
		(18 "In8.Cu" signal "L9GND")
		(20 "In9.Cu" signal "L10")
		(22 "In10.Cu" signal "L11GND")
		(24 "In11.Cu" signal "L12")
		(26 "In12.Cu" signal "L13GND")
		(2 "B.Cu" signal "BOTTOM")
		(9 "F.Adhes" user "F.Adhesive")
		(11 "B.Adhes" user "B.Adhesive")
		(13 "F.Paste" user "Package Geometry/Pastemask Top")
		(15 "B.Paste" user "Package Geometry/Pastemask Bottom")
		(5 "F.SilkS" user "Ref Des/Silkscreen Top")
		(7 "B.SilkS" user "Ref Des/Silkscreen Bottom")
		(1 "F.Mask" user "Board Geometry/Soldermask Top")
		(3 "B.Mask" user "Board Geometry/Soldermask Bottom")
		(17 "Dwgs.User" user "User.Drawings")
		(19 "Cmts.User" user "User.Comments")
		(21 "Eco1.User" user "User.Eco1")
		(23 "Eco2.User" user "User.Eco2")
		(25 "Edge.Cuts" user "Board Geometry/Outline")
		(27 "Margin" user)
		(31 "F.CrtYd" user "Package Geometry/Place Bound Top")
		(29 "B.CrtYd" user "Package Geometry/Place Bound Bottom")
		(35 "F.Fab" user "Ref Des/Assembly Top")
		(33 "B.Fab" user "Ref Des/Assembly Bottom")
	)
	(footprint ""
		(layer "B.Cu")
		(at 88.392 -17.7546 90)
		(property "Reference" "C8T7"
			(at -1.848866 0.752348 90)
			(unlocked yes)
			(layer "B.SilkS")
			(effects
				(font
					(size 1.27 0.9652)
					(thickness 0.1524)
				)
				(justify mirror)
			)
		)
		(property "Value" ""
			(at 0 0 90)
			(layer "B.Fab")
			(effects
				(font
					(size 1.27 1.27)
				)
				(justify mirror)
			)
		)
		(duplicate_pad_numbers_are_jumpers no)
		(fp_rect
			(start 0.500126 1.598422)
			(end -0.500126 -0.201422)
			(stroke
				(width 0)
				(type default)
			)
			(fill no)
			(layer "B.CrtYd")
		)
		(fp_line
			(start 0.500126 -0.201422)
			(end -0.500126 -0.201422)
			(stroke
				(width 0.1)
				(type default)
			)
			(layer "B.Fab")
		)
		(fp_line
			(start -0.500126 -0.201422)
			(end -0.500126 1.598422)
			(stroke
				(width 0.1)
				(type default)
			)
			(layer "B.Fab")
		)
		(fp_line
			(start 0.500126 1.598422)
			(end 0.500126 -0.201422)
			(stroke
				(width 0.1)
				(type default)
			)
			(layer "B.Fab")
		)
		(fp_line
			(start -0.500126 1.598422)
			(end 0.500126 1.598422)
			(stroke
				(width 0.1)
				(type default)
			)
			(layer "B.Fab")
		)
		(pad "1" smd rect
			(at 0 0)
			(size 0.889 0.9906)
			(layers "B.Cu" "B.Mask" "B.Paste")
			(net "PVDDQ_GHJ")
		)
		(pad "2" smd rect
			(at 0 1.397)
			(size 0.889 0.9906)
			(layers "B.Cu" "B.Mask" "B.Paste")
			(net "GND")
		)
		(zone
			(layer "B.Cu")
			(hatch none 0.5)
			(connect_pads
				(clearance 0)
			)
			(min_thickness 0.25)
			(keepout
				(tracks allowed)
				(vias not_allowed)
				(pads allowed)
				(copperpour not_allowed)
				(footprints allowed)
			)
			(placement
				(enabled no)
				(sheetname "")
			)
			(fill
				(thermal_gap 0.5)
				(thermal_bridge_width 0.5)
				(island_removal_mode 0)
			)
			(polygon
				(pts
					(xy 89.3445 -18.2499) (xy 88.8365 -18.2499) (xy 88.8365 -17.2593) (xy 89.3445 -17.2593)
				)
			)
		)
		(zone
			(layer "B.Cu")
			(hatch none 0.5)
			(connect_pads
				(clearance 0)
			)
			(min_thickness 0.25)
			(keepout
				(tracks not_allowed)
				(vias allowed)
				(pads allowed)
				(copperpour not_allowed)
				(footprints allowed)
			)
			(placement
				(enabled no)
				(sheetname "")
			)
			(fill
				(thermal_gap 0.5)
				(thermal_bridge_width 0.5)
				(island_removal_mode 0)
			)
			(polygon
				(pts
					(xy 89.3445 -18.2499) (xy 88.8365 -18.2499) (xy 88.8365 -17.2593) (xy 89.3445 -17.2593)
				)
			)
		)
	)
	(footprint ""
		(layer "B.Cu")
		(at 374.74271 -75.492864 180)
		(property "Reference" "C3R1"
			(at 0 0 0)
			(layer "B.SilkS")
			(hide yes)
			(effects
				(font
					(size 1.27 1.27)
				)
				(justify mirror)
			)
		)
		(property "Value" ""
			(at 0 0 0)
			(layer "B.Fab")
			(effects
				(font
					(size 1.27 1.27)
				)
				(justify mirror)
			)
		)
		(duplicate_pad_numbers_are_jumpers no)
		(fp_rect
			(start 0.2794 0.9144)
			(end -0.2794 -0.1143)
			(stroke
				(width 0)
				(type default)
			)
			(fill no)
			(layer "B.CrtYd")
		)
		(fp_line
			(start 0.2794 0.9144)
			(end 0.2794 -0.1143)
			(stroke
				(width 0.1)
				(type default)
			)
			(layer "B.Fab")
		)
		(fp_line
			(start 0.2794 -0.1143)
			(end -0.2794 -0.1143)
			(stroke
				(width 0.1)
				(type default)
			)
			(layer "B.Fab")
		)
		(fp_line
			(start -0.2794 0.9144)
			(end 0.2794 0.9144)
			(stroke
				(width 0.1)
				(type default)
			)
			(layer "B.Fab")
		)
		(fp_line
			(start -0.2794 -0.1143)
			(end -0.2794 0.9144)
			(stroke
				(width 0.1)
				(type default)
			)
			(layer "B.Fab")
		)
		(pad "1" smd custom
			(at 0 0 90)
			(size 0.10414 0.10414)
			(layers "B.Cu" "B.Mask" "B.Paste")
			(net "P3V3_STBY")
			(options
				(clearance outline)
				(anchor circle)
			)
			(primitives
				(gr_poly
					(pts
						(xy -0.20828 -0.08636) (xy -0.20828 0.08636) (xy -0.08636 0.20828) (xy 0.086614 0.20828) (xy 0.20828 0.086614)
						(xy 0.20828 -0.08636) (xy 0.08636 -0.20828) (xy -0.08636 -0.20828)
					)
					(width 0)
					(fill yes)
				)
			)
		)
		(pad "2" smd custom
			(at 0 0.8001 90)
			(size 0.10414 0.10414)
			(layers "B.Cu" "B.Mask" "B.Paste")
			(net "GND")
			(options
				(clearance outline)
				(anchor circle)
			)
			(primitives
				(gr_poly
					(pts
						(xy -0.20828 -0.08636) (xy -0.20828 0.08636) (xy -0.08636 0.20828) (xy 0.086614 0.20828) (xy 0.20828 0.086614)
						(xy 0.20828 -0.08636) (xy 0.08636 -0.20828) (xy -0.08636 -0.20828)
					)
					(width 0)
					(fill yes)
				)
			)
		)
		(zone
			(layer "B.Cu")
			(hatch none 0.5)
			(connect_pads
				(clearance 0)
			)
			(min_thickness 0.25)
			(keepout
				(tracks allowed)
				(vias not_allowed)
				(pads allowed)
				(copperpour not_allowed)
				(footprints allowed)
			)
			(placement
				(enabled no)
				(sheetname "")
			)
			(fill
				(thermal_gap 0.5)
				(thermal_bridge_width 0.5)
				(island_removal_mode 0)
			)
			(polygon
				(pts
					(xy 374.65508 -75.702414) (xy 374.65508 -76.083414) (xy 374.83034 -76.083414) (xy 374.830594 -75.702414)
				)
			)
		)
		(zone
			(layer "B.Cu")
			(hatch none 0.5)
			(connect_pads
				(clearance 0)
			)
			(min_thickness 0.25)
			(keepout
				(tracks not_allowed)
				(vias allowed)
				(pads allowed)
				(copperpour not_allowed)
				(footprints allowed)
			)
			(placement
				(enabled no)
				(sheetname "")
			)
			(fill
				(thermal_gap 0.5)
				(thermal_bridge_width 0.5)
				(island_removal_mode 0)
			)
			(polygon
				(pts
					(xy 374.65508 -75.702414) (xy 374.65508 -76.083414) (xy 374.83034 -76.083414) (xy 374.830594 -75.702414)
				)
			)
		)
	)
	(footprint ""
		(layer "B.Cu")
		(at 269.559532 -135.4074 90)
		(property "Reference" "C5M2"
			(at -1.848866 0.752348 90)
			(unlocked yes)
			(layer "B.SilkS")
			(effects
				(font
					(size 1.27 0.9652)
					(thickness 0.1524)
				)
				(justify mirror)
			)
		)
		(property "Value" ""
			(at 0 0 90)
			(layer "B.Fab")
			(effects
				(font
					(size 1.27 1.27)
				)
				(justify mirror)
			)
		)
		(duplicate_pad_numbers_are_jumpers no)
		(fp_rect
			(start 0.500126 1.598422)
			(end -0.500126 -0.201422)
			(stroke
				(width 0)
				(type default)
			)
			(fill no)
			(layer "B.CrtYd")
		)
		(fp_line
			(start 0.500126 -0.201422)
			(end -0.500126 -0.201422)
			(stroke
				(width 0.1)
				(type default)
			)
			(layer "B.Fab")
		)
		(fp_line
			(start -0.500126 -0.201422)
			(end -0.500126 1.598422)
			(stroke
				(width 0.1)
				(type default)
			)
			(layer "B.Fab")
		)
		(fp_line
			(start 0.500126 1.598422)
			(end 0.500126 -0.201422)
			(stroke
				(width 0.1)
				(type default)
			)
			(layer "B.Fab")
		)
		(fp_line
			(start -0.500126 1.598422)
			(end 0.500126 1.598422)
			(stroke
				(width 0.1)
				(type default)
			)
			(layer "B.Fab")
		)
		(pad "1" smd rect
			(at 0 0)
			(size 0.889 0.9906)
			(layers "B.Cu" "B.Mask" "B.Paste")
			(net "PVDDQ_DEF")
		)
		(pad "2" smd rect
			(at 0 1.397)
			(size 0.889 0.9906)
			(layers "B.Cu" "B.Mask" "B.Paste")
			(net "GND")
		)
		(zone
			(layer "B.Cu")
			(hatch none 0.5)
			(connect_pads
				(clearance 0)
			)
			(min_thickness 0.25)
			(keepout
				(tracks not_allowed)
				(vias allowed)
				(pads allowed)
				(copperpour not_allowed)
				(footprints allowed)
			)
			(placement
				(enabled no)
				(sheetname "")
			)
			(fill
				(thermal_gap 0.5)
				(thermal_bridge_width 0.5)
				(island_removal_mode 0)
			)
			(polygon
				(pts
					(xy 270.512032 -135.9027) (xy 270.004032 -135.9027) (xy 270.004032 -134.9121) (xy 270.512032 -134.9121)
				)
			)
		)
		(zone
			(layer "B.Cu")
			(hatch none 0.5)
			(connect_pads
				(clearance 0)
			)
			(min_thickness 0.25)
			(keepout
				(tracks allowed)
				(vias not_allowed)
				(pads allowed)
				(copperpour not_allowed)
				(footprints allowed)
			)
			(placement
				(enabled no)
				(sheetname "")
			)
			(fill
				(thermal_gap 0.5)
				(thermal_bridge_width 0.5)
				(island_removal_mode 0)
			)
			(polygon
				(pts
					(xy 270.512032 -135.9027) (xy 270.004032 -135.9027) (xy 270.004032 -134.9121) (xy 270.512032 -134.9121)
				)
			)
		)
	)
)
